FILE_TYPE=LIBRARY_PARTS;
primitive 'SCHOTTKY_AC';
  pin
    'A':
      PIN_NUMBER='(A)';
      INPUT_LOAD='(-0.01,0.01)';
    'C':
      PIN_NUMBER='(C)';
      BIDIRECTIONAL='TRUE';
      INPUT_LOAD='(-0.01,0.01)';
      OUTPUT_LOAD='(1.0,-1.0)';
  end_pin;
  body
    PART_NAME='SCHOTTKY_AC';
    BODY_NAME='SCHOTTKY_AC';
    PHYS_DES_PREFIX='D';
    CLASS='DISCRETE';
  end_body;
end_primitive;

END.
